(kicad_pcb
	(version 20240108)
	(generator "pcbnew")
	(generator_version "8.0")
	(general
		(thickness 1.62)
		(legacy_teardrops no)
	)
	(paper "A4")
	(title_block
		(title "Jetson Orin Baseboard")
		(date "2025-03-12")
		(rev "1.3.4")
		(company "Antmicro Ltd")
		(comment 1 "www.antmicro.com")
		(comment 9 "footprints 672-674 of 677")
	)
	(layers
		(0 "F.Cu" signal)
		(1 "In1.Cu" signal)
		(2 "In2.Cu" signal)
		(3 "In3.Cu" signal)
		(4 "In4.Cu" jumper)
		(5 "In5.Cu" signal)
		(6 "In6.Cu" signal)
		(31 "B.Cu" signal)
		(32 "B.Adhes" user "B.Adhesive")
		(33 "F.Adhes" user "F.Adhesive")
		(34 "B.Paste" user)
		(35 "F.Paste" user)
		(36 "B.SilkS" user "B.Silkscreen")
		(37 "F.SilkS" user "F.Silkscreen")
		(38 "B.Mask" user)
		(39 "F.Mask" user)
		(40 "Dwgs.User" user "User.Drawings")
		(41 "Cmts.User" user "User.Comments")
		(42 "Eco1.User" user "User.Eco1")
		(43 "Eco2.User" user "User.Eco2")
		(44 "Edge.Cuts" user)
		(45 "Margin" user)
		(46 "B.CrtYd" user "B.Courtyard")
		(47 "F.CrtYd" user "F.Courtyard")
		(48 "B.Fab" user)
		(49 "F.Fab" user)
	)
	(footprint "antmicro-footprints:R_0402_1005Metric"
		(layer "B.Cu")
		(at 46.3 80.1 90)
		(descr "Resistor SMD 0402")
		(tags "resistor SMD 0402")
		(property "Reference" "R164"
			(at 3.5 -0.5 -90)
			(layer "B.SilkS")
			(effects
				(font
					(size 0.7 0.7)
					(thickness 0.15)
				)
				(justify left bottom mirror)
			)
		)
		(property "Value" "R_4k7_0402"
			(at 0 -1.4 -90)
			(layer "B.Fab")
			(effects
				(font
					(size 0.7 0.7)
					(thickness 0.15)
				)
				(justify left bottom mirror)
			)
		)
		(property "Footprint" "antmicro-footprints:R_0402_1005Metric"
			(at 0 0 90)
			(layer "F.Fab")
			(hide yes)
			(effects
				(font
					(size 1.27 1.27)
					(thickness 0.15)
				)
			)
		)
		(property "Datasheet" "https://www.bourns.com/docs/product-datasheets/cr.pdf"
			(at 0 0 90)
			(layer "F.Fab")
			(hide yes)
			(effects
				(font
					(size 1.27 1.27)
					(thickness 0.15)
				)
			)
		)
		(property "Author" "Antmicro"
			(at 127.55 32.65 0)
			(layer "B.Fab")
			(hide yes)
			(effects
				(font
					(size 1 1)
					(thickness 0.15)
				)
				(justify mirror)
			)
		)
		(property "License" "Apache-2.0"
			(at 127.55 32.65 0)
			(layer "B.Fab")
			(hide yes)
			(effects
				(font
					(size 1 1)
					(thickness 0.15)
				)
				(justify mirror)
			)
		)
		(property "MPN" "CR0402-FX-4701GLF"
			(at 127.55 32.65 0)
			(layer "B.Fab")
			(hide yes)
			(effects
				(font
					(size 1 1)
					(thickness 0.15)
				)
				(justify mirror)
			)
		)
		(property "Manufacturer" "Bourns"
			(at 127.55 32.65 0)
			(layer "B.Fab")
			(hide yes)
			(effects
				(font
					(size 1 1)
					(thickness 0.15)
				)
				(justify mirror)
			)
		)
		(property "Tolerance" "1%"
			(at 127.55 32.65 0)
			(layer "B.Fab")
			(hide yes)
			(effects
				(font
					(size 1 1)
					(thickness 0.15)
				)
				(justify mirror)
			)
		)
		(property "Val" "4k7"
			(at 127.55 32.65 0)
			(layer "B.Fab")
			(hide yes)
			(effects
				(font
					(size 1 1)
					(thickness 0.15)
				)
				(justify mirror)
			)
		)
		(sheetname "Supply")
		(sheetfile "supply.kicad_sch")
		(attr smd)
		(fp_rect
			(start -0.925 0.47)
			(end 0.925 -0.47)
			(stroke
				(width 0.05)
				(type default)
			)
			(fill none)
			(layer "B.CrtYd")
		)
		(fp_rect
			(start -0.5 0.25)
			(end 0.5 -0.25)
			(stroke
				(width 0.15)
				(type solid)
			)
			(fill none)
			(layer "B.Fab")
		)
		(fp_text user "Author: Antmicro"
			(at -0.95 -4.169 -90)
			(layer "B.Fab")
			(hide yes)
			(effects
				(font
					(size 0.7 0.7)
					(thickness 0.15)
				)
				(justify left bottom mirror)
			)
		)
		(fp_text user "${REFERENCE}"
			(at -0.95 -3.168 -90)
			(layer "B.Fab")
			(hide yes)
			(effects
				(font
					(size 0.7 0.7)
					(thickness 0.15)
				)
				(justify left bottom mirror)
			)
		)
		(fp_text user "License: Apache-2.0"
			(at -0.95 -5.169 -90)
			(layer "B.Fab")
			(hide yes)
			(effects
				(font
					(size 0.7 0.7)
					(thickness 0.15)
				)
				(justify left bottom mirror)
			)
		)
		(pad "1" smd roundrect
			(at -0.48 0 90)
			(size 0.59 0.64)
			(layers "B.Cu" "B.Paste" "B.Mask")
			(roundrect_rratio 0.25)
			(net 135 "Net-(Q18-G)")
			(pintype "passive")
		)
		(pad "2" smd roundrect
			(at 0.48 0 90)
			(size 0.59 0.64)
			(layers "B.Cu" "B.Paste" "B.Mask")
			(roundrect_rratio 0.25)
			(net 328 "/Supply/VCC_IN")
			(pintype "passive")
		)
	)
	(footprint "antmicro-footprints:C_0402_1005Metric"
		(layer "B.Cu")
		(at 90.025 83.5)
		(descr "Capacitor SMD 0402")
		(tags "capacitor SMD 0402")
		(property "Reference" "C138"
			(at -0.875 0.47 180)
			(layer "B.SilkS")
			(effects
				(font
					(size 0.7 0.7)
					(thickness 0.15)
				)
				(justify left bottom mirror)
			)
		)
		(property "Value" "C_100n_0402"
			(at 0 -1.4 180)
			(layer "B.Fab")
			(effects
				(font
					(size 0.7 0.7)
					(thickness 0.15)
				)
				(justify left bottom mirror)
			)
		)
		(property "Footprint" "antmicro-footprints:C_0402_1005Metric"
			(at 0 0 0)
			(layer "F.Fab")
			(hide yes)
			(effects
				(font
					(size 1.27 1.27)
					(thickness 0.15)
				)
			)
		)
		(property "Datasheet" "https://www.murata.com/products/productdetail?partno=GRM155R61H104KE14%23"
			(at 0 0 0)
			(layer "F.Fab")
			(hide yes)
			(effects
				(font
					(size 1.27 1.27)
					(thickness 0.15)
				)
			)
		)
		(property "Author" "Antmicro"
			(at 0 0 0)
			(layer "B.Fab")
			(hide yes)
			(effects
				(font
					(size 1 1)
					(thickness 0.15)
				)
				(justify mirror)
			)
		)
		(property "Dielectric" "X5R"
			(at 0 0 0)
			(layer "B.Fab")
			(hide yes)
			(effects
				(font
					(size 1 1)
					(thickness 0.15)
				)
				(justify mirror)
			)
		)
		(property "License" "Apache-2.0"
			(at 0 0 0)
			(layer "B.Fab")
			(hide yes)
			(effects
				(font
					(size 1 1)
					(thickness 0.15)
				)
				(justify mirror)
			)
		)
		(property "MPN" "GRM155R61H104KE14D"
			(at 0 0 0)
			(layer "B.Fab")
			(hide yes)
			(effects
				(font
					(size 1 1)
					(thickness 0.15)
				)
				(justify mirror)
			)
		)
		(property "Manufacturer" "Murata"
			(at 0 0 0)
			(layer "B.Fab")
			(hide yes)
			(effects
				(font
					(size 1 1)
					(thickness 0.15)
				)
				(justify mirror)
			)
		)
		(property "Val" "100n"
			(at 0 0 0)
			(layer "B.Fab")
			(hide yes)
			(effects
				(font
					(size 1 1)
					(thickness 0.15)
				)
				(justify mirror)
			)
		)
		(property "Voltage" "50V"
			(at 0 0 0)
			(layer "B.Fab")
			(hide yes)
			(effects
				(font
					(size 1 1)
					(thickness 0.15)
				)
				(justify mirror)
			)
		)
		(sheetname "HDMI")
		(sheetfile "hdmi.kicad_sch")
		(attr smd)
		(fp_rect
			(start -0.925 0.47)
			(end 0.925 -0.47)
			(stroke
				(width 0.05)
				(type default)
			)
			(fill none)
			(layer "B.CrtYd")
		)
		(fp_line
			(start -0.494 -0.248)
			(end 0.504 -0.248)
			(stroke
				(width 0.15)
				(type solid)
			)
			(layer "B.Fab")
		)
		(fp_line
			(start -0.494 0.25)
			(end -0.494 -0.248)
			(stroke
				(width 0.15)
				(type solid)
			)
			(layer "B.Fab")
		)
		(fp_line
			(start 0.504 -0.248)
			(end 0.504 0.25)
			(stroke
				(width 0.15)
				(type solid)
			)
			(layer "B.Fab")
		)
		(fp_line
			(start 0.504 0.25)
			(end -0.494 0.25)
			(stroke
				(width 0.15)
				(type solid)
			)
			(layer "B.Fab")
		)
		(fp_text user "${REFERENCE}"
			(at -0.932 -3.168 180)
			(layer "B.Fab")
			(hide yes)
			(effects
				(font
					(size 0.7 0.7)
					(thickness 0.15)
				)
				(justify left bottom mirror)
			)
		)
		(fp_text user "License: Apache-2.0"
			(at -0.932 -5.17 180)
			(layer "B.Fab")
			(hide yes)
			(effects
				(font
					(size 0.7 0.7)
					(thickness 0.15)
				)
				(justify left bottom mirror)
			)
		)
		(fp_text user "Author: Antmicro"
			(at -0.932 -4.17 180)
			(layer "B.Fab")
			(hide yes)
			(effects
				(font
					(size 0.7 0.7)
					(thickness 0.15)
				)
				(justify left bottom mirror)
			)
		)
		(pad "1" smd roundrect
			(at -0.48 0)
			(size 0.59 0.64)
			(layers "B.Cu" "B.Paste" "B.Mask")
			(roundrect_rratio 0.25)
			(net 35 "DP1_AUX_N")
			(pintype "passive")
		)
		(pad "2" smd roundrect
			(at 0.48 0)
			(size 0.59 0.64)
			(layers "B.Cu" "B.Paste" "B.Mask")
			(roundrect_rratio 0.25)
			(net 668 "/HDMI/DP_MUX_AUX_B-")
			(pintype "passive")
		)
	)
	(footprint "antmicro-footprints:C_2220_5650Metric"
		(layer "B.Cu")
		(at 41.74 103.23 180)
		(descr "Capacitor SMD 2220")
		(tags "capacitor SMD 2220")
		(property "Reference" "C79"
			(at 1.54 3.06 0)
			(layer "B.SilkS")
			(effects
				(font
					(size 0.7 0.7)
					(thickness 0.15)
				)
				(justify left bottom mirror)
			)
		)
		(property "Value" "C_22u_100V_2220"
			(at 0 -3.9 0)
			(layer "B.Fab")
			(effects
				(font
					(size 0.7 0.7)
					(thickness 0.15)
				)
				(justify left bottom mirror)
			)
		)
		(property "Footprint" "antmicro-footprints:C_2220_5650Metric"
			(at 0 0 180)
			(layer "F.Fab")
			(hide yes)
			(effects
				(font
					(size 1.27 1.27)
					(thickness 0.15)
				)
			)
		)
		(property "Datasheet" "https://product.tdk.com/en/search/capacitor/ceramic/mlcc/info?part_no=C5750X7S2A226M280KB"
			(at 0 0 180)
			(layer "F.Fab")
			(hide yes)
			(effects
				(font
					(size 1.27 1.27)
					(thickness 0.15)
				)
			)
		)
		(property "Author" "Antmicro"
			(at 83.48 206.46 0)
			(layer "B.Fab")
			(hide yes)
			(effects
				(font
					(size 1 1)
					(thickness 0.15)
				)
				(justify mirror)
			)
		)
		(property "Dielectric" "X7S"
			(at 83.48 206.46 0)
			(layer "B.Fab")
			(hide yes)
			(effects
				(font
					(size 1 1)
					(thickness 0.15)
				)
				(justify mirror)
			)
		)
		(property "License" "Apache-2.0"
			(at 83.48 206.46 0)
			(layer "B.Fab")
			(hide yes)
			(effects
				(font
					(size 1 1)
					(thickness 0.15)
				)
				(justify mirror)
			)
		)
		(property "MPN" "C5750X7S2A226M280KB"
			(at 83.48 206.46 0)
			(layer "B.Fab")
			(hide yes)
			(effects
				(font
					(size 1 1)
					(thickness 0.15)
				)
				(justify mirror)
			)
		)
		(property "Manufacturer" "TDK"
			(at 83.48 206.46 0)
			(layer "B.Fab")
			(hide yes)
			(effects
				(font
					(size 1 1)
					(thickness 0.15)
				)
				(justify mirror)
			)
		)
		(property "Public" "False"
			(at 83.48 206.46 0)
			(layer "B.Fab")
			(hide yes)
			(effects
				(font
					(size 1 1)
					(thickness 0.15)
				)
				(justify mirror)
			)
		)
		(property "Val" "22u"
			(at 83.48 206.46 0)
			(layer "B.Fab")
			(hide yes)
			(effects
				(font
					(size 1 1)
					(thickness 0.15)
				)
				(justify mirror)
			)
		)
		(property "Voltage" "100V"
			(at 83.48 206.46 0)
			(layer "B.Fab")
			(hide yes)
			(effects
				(font
					(size 1 1)
					(thickness 0.15)
				)
				(justify mirror)
			)
		)
		(sheetname "Ethernet")
		(sheetfile "ethernet.kicad_sch")
		(attr smd)
		(fp_line
			(start 1.415 2.61)
			(end -1.415 2.61)
			(stroke
				(width 0.15)
				(type solid)
			)
			(layer "B.SilkS")
		)
		(fp_line
			(start 1.415 -2.61)
			(end -1.415 -2.61)
			(stroke
				(width 0.15)
				(type solid)
			)
			(layer "B.SilkS")
		)
		(fp_rect
			(start -3.7 2.95)
			(end 3.7 -2.95)
			(stroke
				(width 0.05)
				(type solid)
			)
			(fill none)
			(layer "B.CrtYd")
		)
		(fp_rect
			(start -2.85 2.5)
			(end 2.85 -2.5)
			(stroke
				(width 0.15)
				(type solid)
			)
			(fill none)
			(layer "B.Fab")
		)
		(fp_text user "Author: Antmicro"
			(at -3.7 -7.9 0)
			(layer "B.Fab")
			(hide yes)
			(effects
				(font
					(size 0.7 0.7)
					(thickness 0.15)
				)
				(justify left bottom mirror)
			)
		)
		(fp_text user "License: Apache-2.0"
			(at -3.7 -6.9 0)
			(layer "B.Fab")
			(hide yes)
			(effects
				(font
					(size 0.7 0.7)
					(thickness 0.15)
				)
				(justify left bottom mirror)
			)
		)
		(fp_text user "${REFERENCE}"
			(at -3.7 -5.9 0)
			(layer "B.Fab")
			(hide yes)
			(effects
				(font
					(size 0.7 0.7)
					(thickness 0.15)
				)
				(justify left bottom mirror)
			)
		)
		(pad "1" smd roundrect
			(at -2.55 0 180)
			(size 1.8 5.4)
			(layers "B.Cu" "B.Paste" "B.Mask")
			(roundrect_rratio 0.138889)
			(net 106 "GNDD")
			(pintype "passive")
		)
		(pad "2" smd roundrect
			(at 2.55 0 180)
			(size 1.8 5.4)
			(layers "B.Cu" "B.Paste" "B.Mask")
			(roundrect_rratio 0.138889)
			(net 105 "/Ethernet/VDD")
			(pintype "passive")
		)
	)
)
